# T6G (Grand Teton) — schematic netlist excerpt (pin names and nets, part order shuffled) for the footprints in the layout excerpt that follows; sources: Cadence DE-HDL packaged netlist, KiCad conversion of 04192023_DAF0TMB3IC0_F0TG_MB_C_brd_V02_OCP.brd

C3934  Q_CAP  22UF 4V 20% X6S  pkg C0402  page 70 : A = PVDD11_S3_P0 ; B = GND
PR230  Q_RES  40.2K 1% CHIP  pkg 0402LF  page 217 : A = P5V_AUX ; B = PVDDCR_CPU1_P1_VMON
PC354_3  Q_CAP  22UF 4V 20% X6S  pkg C0805  page 216 : A = PVDDCR_SOC_P1 ; B = GND

(kicad_pcb
	(version 20260206)
	(generator "pcbnew")
	(generator_version "10.0")
	(general
		(thickness 1.6)
		(legacy_teardrops no)
	)
	(paper "A4")
	(title_block
		(title "04192023_DAF0TMB3IC0_F0TG_MB_C_brd_V02_OCP.brd")
		(comment 1 "Grand Teton / footprints 6598-6600 of 8354")
	)
	(layers
		(0 "F.Cu" signal "TOP")
		(4 "In1.Cu" signal "GND")
		(6 "In2.Cu" signal "IN1")
		(8 "In3.Cu" signal "GND1")
		(10 "In4.Cu" signal "IN2")
		(12 "In5.Cu" signal "GND2")
		(14 "In6.Cu" signal "IN3")
		(16 "In7.Cu" signal "GND3")
		(18 "In8.Cu" signal "VCC")
		(20 "In9.Cu" signal "VCC1")
		(22 "In10.Cu" signal "GND4")
		(24 "In11.Cu" signal "IN4")
		(26 "In12.Cu" signal "GND5")
		(28 "In13.Cu" signal "IN5")
		(30 "In14.Cu" signal "GND6")
		(32 "In15.Cu" signal "IN6")
		(34 "In16.Cu" signal "GND7")
		(2 "B.Cu" signal "BOTTOM")
		(9 "F.Adhes" user "F.Adhesive")
		(11 "B.Adhes" user "B.Adhesive")
		(13 "F.Paste" user "Package Geometry/Pastemask Top")
		(15 "B.Paste" user "Package Geometry/Pastemask Bottom")
		(5 "F.SilkS" user "Ref Des/Silkscreen Top")
		(7 "B.SilkS" user "Ref Des/Silkscreen Bottom")
		(1 "F.Mask" user "Board Geometry/Soldermask Top")
		(3 "B.Mask" user "Board Geometry/Soldermask Bottom")
		(17 "Dwgs.User" user "User.Drawings")
		(19 "Cmts.User" user "User.Comments")
		(21 "Eco1.User" user "User.Eco1")
		(23 "Eco2.User" user "User.Eco2")
		(25 "Edge.Cuts" user "Board Geometry/Outline")
		(27 "Margin" user)
		(31 "F.CrtYd" user "Package Geometry/Place Bound Top")
		(29 "B.CrtYd" user "Package Geometry/Place Bound Bottom")
		(35 "F.Fab" user "Ref Des/Assembly Top")
		(33 "B.Fab" user "Ref Des/Assembly Bottom")
	)
	(footprint ""
		(layer "B.Cu")
		(at 358.089454 -266.00531)
		(property "Reference" "C3934"
			(at 0 0 0)
			(layer "B.SilkS")
			(hide yes)
			(effects
				(font
					(size 1.27 1.27)
				)
				(justify mirror)
			)
		)
		(property "Value" ""
			(at 0 0 0)
			(layer "B.Fab")
			(effects
				(font
					(size 1.27 1.27)
				)
				(justify mirror)
			)
		)
		(duplicate_pad_numbers_are_jumpers no)
		(fp_line
			(start -0.7874 -0.4064)
			(end -0.7874 0.4064)
			(stroke
				(width 0.1524)
				(type default)
			)
			(layer "B.SilkS")
		)
		(fp_line
			(start -0.7874 0.4064)
			(end 0.7874 0.4064)
			(stroke
				(width 0.1524)
				(type default)
			)
			(layer "B.SilkS")
		)
		(fp_line
			(start 0.7874 -0.4064)
			(end -0.7874 -0.4064)
			(stroke
				(width 0.1524)
				(type default)
			)
			(layer "B.SilkS")
		)
		(fp_line
			(start 0.7874 0.4064)
			(end 0.7874 -0.4064)
			(stroke
				(width 0.1524)
				(type default)
			)
			(layer "B.SilkS")
		)
		(fp_line
			(start -0.67945 -0.3048)
			(end -0.67945 0.3048)
			(stroke
				(width 0.1)
				(type default)
			)
			(layer "B.Fab")
		)
		(fp_line
			(start -0.67945 0.3048)
			(end -0.120396 0.3048)
			(stroke
				(width 0.1)
				(type default)
			)
			(layer "B.Fab")
		)
		(fp_line
			(start -0.12065 -0.3048)
			(end -0.67945 -0.3048)
			(stroke
				(width 0.1)
				(type default)
			)
			(layer "B.Fab")
		)
		(fp_line
			(start -0.12065 -0.2794)
			(end -0.12065 -0.3048)
			(stroke
				(width 0.1)
				(type default)
			)
			(layer "B.Fab")
		)
		(fp_line
			(start -0.120396 0.2794)
			(end 0.12065 0.2794)
			(stroke
				(width 0.1)
				(type default)
			)
			(layer "B.Fab")
		)
		(fp_line
			(start -0.120396 0.3048)
			(end -0.120396 0.2794)
			(stroke
				(width 0.1)
				(type default)
			)
			(layer "B.Fab")
		)
		(fp_line
			(start 0.12065 -0.305054)
			(end 0.12065 -0.2794)
			(stroke
				(width 0.1)
				(type default)
			)
			(layer "B.Fab")
		)
		(fp_line
			(start 0.12065 -0.2794)
			(end -0.12065 -0.2794)
			(stroke
				(width 0.1)
				(type default)
			)
			(layer "B.Fab")
		)
		(fp_line
			(start 0.12065 0.2794)
			(end 0.12065 0.3048)
			(stroke
				(width 0.1)
				(type default)
			)
			(layer "B.Fab")
		)
		(fp_line
			(start 0.12065 0.3048)
			(end 0.67945 0.3048)
			(stroke
				(width 0.1)
				(type default)
			)
			(layer "B.Fab")
		)
		(fp_line
			(start 0.67945 -0.305054)
			(end 0.12065 -0.305054)
			(stroke
				(width 0.1)
				(type default)
			)
			(layer "B.Fab")
		)
		(fp_line
			(start 0.67945 0.3048)
			(end 0.67945 -0.305054)
			(stroke
				(width 0.1)
				(type default)
			)
			(layer "B.Fab")
		)
		(pad "1" smd circle
			(at 0.40005 0 180)
			(size 0 0)
			(layers "B.Cu" "B.Mask" "B.Paste")
			(net "PVDD11_S3_P0")
		)
		(pad "2" smd circle
			(at -0.40005 0 180)
			(size 0 0)
			(layers "B.Cu" "B.Mask" "B.Paste")
			(net "GND")
		)
	)
	(footprint ""
		(layer "B.Cu")
		(at 136.868154 -165.145212 90)
		(property "Reference" "PC354_3"
			(at 0 0 90)
			(layer "B.SilkS")
			(hide yes)
			(effects
				(font
					(size 1.27 1.27)
				)
				(justify mirror)
			)
		)
		(property "Value" ""
			(at 0 0 90)
			(layer "B.Fab")
			(effects
				(font
					(size 1.27 1.27)
				)
				(justify mirror)
			)
		)
		(duplicate_pad_numbers_are_jumpers no)
		(fp_line
			(start 1.524 -0.762)
			(end -1.524 -0.762)
			(stroke
				(width 0.1524)
				(type default)
			)
			(layer "B.SilkS")
		)
		(fp_line
			(start -1.524 -0.762)
			(end -1.524 0.762)
			(stroke
				(width 0.1524)
				(type default)
			)
			(layer "B.SilkS")
		)
		(fp_line
			(start 1.524 0.762)
			(end 1.524 -0.762)
			(stroke
				(width 0.1524)
				(type default)
			)
			(layer "B.SilkS")
		)
		(fp_line
			(start -1.524 0.762)
			(end 1.524 0.762)
			(stroke
				(width 0.1524)
				(type default)
			)
			(layer "B.SilkS")
		)
		(fp_line
			(start 1.1049 -0.724916)
			(end 1.1049 0.724916)
			(stroke
				(width 0.1)
				(type default)
			)
			(layer "B.Fab")
		)
		(fp_line
			(start -1.1049 -0.724916)
			(end 1.1049 -0.724916)
			(stroke
				(width 0.1)
				(type default)
			)
			(layer "B.Fab")
		)
		(fp_line
			(start 1.1049 0.724916)
			(end -1.1049 0.724916)
			(stroke
				(width 0.1)
				(type default)
			)
			(layer "B.Fab")
		)
		(fp_line
			(start -1.1049 0.724916)
			(end -1.1049 -0.724916)
			(stroke
				(width 0.1)
				(type default)
			)
			(layer "B.Fab")
		)
		(pad "1" smd rect
			(at 0.889 0 90)
			(size 1.016 1.27)
			(layers "B.Cu" "B.Mask" "B.Paste")
			(net "PVDDCR_SOC_P1")
		)
		(pad "2" smd rect
			(at -0.889 0 90)
			(size 1.016 1.27)
			(layers "B.Cu" "B.Mask" "B.Paste")
			(net "GND")
		)
	)
	(footprint ""
		(layer "B.Cu")
		(at 35.306 -361.95)
		(property "Reference" "PR230"
			(at 0 0 0)
			(layer "B.SilkS")
			(hide yes)
			(effects
				(font
					(size 1.27 1.27)
				)
				(justify mirror)
			)
		)
		(property "Value" ""
			(at 0 0 0)
			(layer "B.Fab")
			(effects
				(font
					(size 1.27 1.27)
				)
				(justify mirror)
			)
		)
		(duplicate_pad_numbers_are_jumpers no)
		(fp_line
			(start -0.7874 -0.4064)
			(end -0.7874 0.4064)
			(stroke
				(width 0.1524)
				(type default)
			)
			(layer "B.SilkS")
		)
		(fp_line
			(start -0.7874 0.4064)
			(end 0.7874 0.4064)
			(stroke
				(width 0.1524)
				(type default)
			)
			(layer "B.SilkS")
		)
		(fp_line
			(start 0.7874 -0.4064)
			(end -0.7874 -0.4064)
			(stroke
				(width 0.1524)
				(type default)
			)
			(layer "B.SilkS")
		)
		(fp_line
			(start 0.7874 0.4064)
			(end 0.7874 -0.4064)
			(stroke
				(width 0.1524)
				(type default)
			)
			(layer "B.SilkS")
		)
		(fp_line
			(start -0.67945 -0.3048)
			(end -0.67945 0.3048)
			(stroke
				(width 0.1)
				(type default)
			)
			(layer "B.Fab")
		)
		(fp_line
			(start -0.67945 0.3048)
			(end -0.120396 0.3048)
			(stroke
				(width 0.1)
				(type default)
			)
			(layer "B.Fab")
		)
		(fp_line
			(start -0.12065 -0.3048)
			(end -0.67945 -0.3048)
			(stroke
				(width 0.1)
				(type default)
			)
			(layer "B.Fab")
		)
		(fp_line
			(start -0.12065 -0.2794)
			(end -0.12065 -0.3048)
			(stroke
				(width 0.1)
				(type default)
			)
			(layer "B.Fab")
		)
		(fp_line
			(start -0.120396 0.2794)
			(end 0.12065 0.2794)
			(stroke
				(width 0.1)
				(type default)
			)
			(layer "B.Fab")
		)
		(fp_line
			(start -0.120396 0.3048)
			(end -0.120396 0.2794)
			(stroke
				(width 0.1)
				(type default)
			)
			(layer "B.Fab")
		)
		(fp_line
			(start 0.12065 -0.305054)
			(end 0.12065 -0.2794)
			(stroke
				(width 0.1)
				(type default)
			)
			(layer "B.Fab")
		)
		(fp_line
			(start 0.12065 -0.2794)
			(end -0.12065 -0.2794)
			(stroke
				(width 0.1)
				(type default)
			)
			(layer "B.Fab")
		)
		(fp_line
			(start 0.12065 0.2794)
			(end 0.12065 0.3048)
			(stroke
				(width 0.1)
				(type default)
			)
			(layer "B.Fab")
		)
		(fp_line
			(start 0.12065 0.3048)
			(end 0.67945 0.3048)
			(stroke
				(width 0.1)
				(type default)
			)
			(layer "B.Fab")
		)
		(fp_line
			(start 0.67945 -0.305054)
			(end 0.12065 -0.305054)
			(stroke
				(width 0.1)
				(type default)
			)
			(layer "B.Fab")
		)
		(fp_line
			(start 0.67945 0.3048)
			(end 0.67945 -0.305054)
			(stroke
				(width 0.1)
				(type default)
			)
			(layer "B.Fab")
		)
		(pad "1" smd circle
			(at 0.40005 0 180)
			(size 0 0)
			(layers "B.Cu" "B.Mask" "B.Paste")
			(net "P5V_AUX")
		)
		(pad "2" smd circle
			(at -0.40005 0 180)
			(size 0 0)
			(layers "B.Cu" "B.Mask" "B.Paste")
			(net "PVDDCR_CPU1_P1_VMON")
		)
	)
)
